(kicad_sch (version 20230121) (generator eeschema)

  (paper "A3")

  (title_block
    (title "Kria K26 Devboard")
    (date "2024-03-26")
    (rev "1.2.5")
    (comment 1 "www.antmicro.com")
    (comment 2 "Antmicro Ltd.")
  )

  (junction (at 156.21 59.69) (diameter 0) (color 0 0 0 0)
  )
  (junction (at 127 93.98) (diameter 0) (color 0 0 0 0)
  )
  (junction (at 122.555 107.95) (diameter 0) (color 0 0 0 0)
  )
  (junction (at 122.555 93.98) (diameter 0) (color 0 0 0 0)
  )
  (junction (at 149.86 143.51) (diameter 0) (color 0 0 0 0)
  )
  (junction (at 125.73 107.95) (diameter 0) (color 0 0 0 0)
  )
  (junction (at 151.13 107.95) (diameter 0) (color 0 0 0 0)
  )
  (junction (at 151.13 59.69) (diameter 0) (color 0 0 0 0)
  )
  (junction (at 152.4 93.98) (diameter 0) (color 0 0 0 0)
  )
  (junction (at 151.13 57.15) (diameter 0) (color 0 0 0 0)
  )
  (junction (at 151.13 93.98) (diameter 0) (color 0 0 0 0)
  )
  (junction (at 149.86 140.97) (diameter 0) (color 0 0 0 0)
  )
  (junction (at 151.13 99.06) (diameter 0) (color 0 0 0 0)
  )
  (junction (at 170.18 59.69) (diameter 0) (color 0 0 0 0)
  )
  (junction (at 127 57.15) (diameter 0) (color 0 0 0 0)
  )
  (junction (at 170.18 93.98) (diameter 0) (color 0 0 0 0)
  )
  (junction (at 161.29 93.98) (diameter 0) (color 0 0 0 0)
  )
  (junction (at 161.29 99.06) (diameter 0) (color 0 0 0 0)
  )
  (junction (at 166.37 59.69) (diameter 0) (color 0 0 0 0)
  )
  (junction (at 124.46 140.97) (diameter 0) (color 0 0 0 0)
  )
  (junction (at 153.67 143.51) (diameter 0) (color 0 0 0 0)
  )

  (no_connect (at 125.73 143.51))
  (no_connect (at 128.27 96.52))
  (no_connect (at 128.27 59.69))

  (wire (pts (xy 125.73 140.97) (xy 124.46 140.97))
    (stroke (width 0) (type default))
  )
  (wire (pts (xy 127 83.185) (xy 136.525 83.185))
    (stroke (width 0) (type default))
  )
  (wire (pts (xy 151.13 46.355) (xy 151.13 57.15))
    (stroke (width 0) (type default))
  )
  (wire (pts (xy 135.89 46.355) (xy 127 46.355))
    (stroke (width 0) (type default))
  )
  (wire (pts (xy 118.745 93.98) (xy 122.555 93.98))
    (stroke (width 0) (type default))
  )
  (polyline (pts (xy 104.14 123.825) (xy 104.14 96.52))
    (stroke (width 0) (type default))
  )

  (wire (pts (xy 161.29 93.98) (xy 161.29 99.06))
    (stroke (width 0) (type default))
  )
  (wire (pts (xy 156.21 59.69) (xy 156.21 63.5))
    (stroke (width 0) (type default))
  )
  (wire (pts (xy 170.18 59.69) (xy 179.07 59.69))
    (stroke (width 0) (type default))
  )
  (wire (pts (xy 151.13 59.69) (xy 156.21 59.69))
    (stroke (width 0) (type default))
  )
  (wire (pts (xy 139.065 130.81) (xy 149.86 130.81))
    (stroke (width 0) (type default))
  )
  (wire (pts (xy 123.825 148.59) (xy 125.73 148.59))
    (stroke (width 0) (type default))
  )
  (wire (pts (xy 151.13 59.69) (xy 151.13 57.15))
    (stroke (width 0) (type default))
  )
  (wire (pts (xy 161.29 93.98) (xy 170.18 93.98))
    (stroke (width 0) (type default))
  )
  (wire (pts (xy 170.18 93.98) (xy 170.18 143.51))
    (stroke (width 0) (type default))
  )
  (wire (pts (xy 166.37 59.69) (xy 166.37 58.42))
    (stroke (width 0) (type default))
  )
  (wire (pts (xy 153.67 143.51) (xy 170.18 143.51))
    (stroke (width 0) (type default))
  )
  (wire (pts (xy 124.46 140.97) (xy 124.46 130.81))
    (stroke (width 0) (type default))
  )
  (wire (pts (xy 147.32 143.51) (xy 149.86 143.51))
    (stroke (width 0) (type default))
  )
  (wire (pts (xy 151.13 101.6) (xy 151.13 99.06))
    (stroke (width 0) (type default))
  )
  (wire (pts (xy 161.29 99.06) (xy 161.29 101.6))
    (stroke (width 0) (type default))
  )
  (polyline (pts (xy 125.095 96.52) (xy 125.095 123.825))
    (stroke (width 0) (type default))
  )

  (wire (pts (xy 125.73 107.95) (xy 122.555 107.95))
    (stroke (width 0) (type default))
  )
  (wire (pts (xy 149.86 99.06) (xy 151.13 99.06))
    (stroke (width 0) (type default))
  )
  (wire (pts (xy 124.46 130.81) (xy 133.985 130.81))
    (stroke (width 0) (type default))
  )
  (wire (pts (xy 149.86 143.51) (xy 149.86 140.97))
    (stroke (width 0) (type default))
  )
  (wire (pts (xy 126.365 64.77) (xy 126.365 66.675))
    (stroke (width 0) (type default))
  )
  (wire (pts (xy 141.605 83.185) (xy 152.4 83.185))
    (stroke (width 0) (type default))
  )
  (wire (pts (xy 122.555 97.155) (xy 122.555 93.98))
    (stroke (width 0) (type default))
  )
  (wire (pts (xy 151.13 107.95) (xy 125.73 107.95))
    (stroke (width 0) (type default))
  )
  (polyline (pts (xy 125.095 123.825) (xy 104.14 123.825))
    (stroke (width 0) (type default))
  )

  (wire (pts (xy 152.4 93.98) (xy 161.29 93.98))
    (stroke (width 0) (type default))
  )
  (wire (pts (xy 156.21 59.69) (xy 166.37 59.69))
    (stroke (width 0) (type default))
  )
  (wire (pts (xy 152.4 93.98) (xy 151.13 93.98))
    (stroke (width 0) (type default))
  )
  (wire (pts (xy 153.67 143.51) (xy 153.67 145.415))
    (stroke (width 0) (type default))
  )
  (wire (pts (xy 149.86 130.81) (xy 149.86 140.97))
    (stroke (width 0) (type default))
  )
  (wire (pts (xy 149.86 59.69) (xy 151.13 59.69))
    (stroke (width 0) (type default))
  )
  (polyline (pts (xy 104.14 96.52) (xy 125.095 96.52))
    (stroke (width 0) (type default))
  )

  (wire (pts (xy 152.4 83.185) (xy 152.4 93.98))
    (stroke (width 0) (type default))
  )
  (wire (pts (xy 128.27 101.6) (xy 125.73 101.6))
    (stroke (width 0) (type default))
  )
  (wire (pts (xy 151.13 57.15) (xy 149.86 57.15))
    (stroke (width 0) (type default))
  )
  (wire (pts (xy 126.365 64.77) (xy 128.27 64.77))
    (stroke (width 0) (type default))
  )
  (wire (pts (xy 127 57.15) (xy 121.92 57.15))
    (stroke (width 0) (type default))
  )
  (wire (pts (xy 128.27 57.15) (xy 127 57.15))
    (stroke (width 0) (type default))
  )
  (wire (pts (xy 149.86 143.51) (xy 153.67 143.51))
    (stroke (width 0) (type default))
  )
  (wire (pts (xy 122.555 104.775) (xy 122.555 107.95))
    (stroke (width 0) (type default))
  )
  (wire (pts (xy 151.13 99.06) (xy 153.67 99.06))
    (stroke (width 0) (type default))
  )
  (wire (pts (xy 151.13 96.52) (xy 151.13 93.98))
    (stroke (width 0) (type default))
  )
  (wire (pts (xy 166.37 59.69) (xy 170.18 59.69))
    (stroke (width 0) (type default))
  )
  (wire (pts (xy 151.13 106.68) (xy 151.13 107.95))
    (stroke (width 0) (type default))
  )
  (wire (pts (xy 149.86 140.97) (xy 147.32 140.97))
    (stroke (width 0) (type default))
  )
  (wire (pts (xy 127 93.98) (xy 127 83.185))
    (stroke (width 0) (type default))
  )
  (wire (pts (xy 123.825 149.86) (xy 123.825 148.59))
    (stroke (width 0) (type default))
  )
  (wire (pts (xy 149.86 93.98) (xy 151.13 93.98))
    (stroke (width 0) (type default))
  )
  (wire (pts (xy 122.555 93.98) (xy 127 93.98))
    (stroke (width 0) (type default))
  )
  (wire (pts (xy 147.32 146.05) (xy 149.86 146.05))
    (stroke (width 0) (type default))
  )
  (wire (pts (xy 125.73 101.6) (xy 125.73 107.95))
    (stroke (width 0) (type default))
  )
  (wire (pts (xy 161.29 106.68) (xy 161.29 107.95))
    (stroke (width 0) (type default))
  )
  (wire (pts (xy 170.18 93.98) (xy 170.18 59.69))
    (stroke (width 0) (type default))
  )
  (wire (pts (xy 127 46.355) (xy 127 57.15))
    (stroke (width 0) (type default))
  )
  (wire (pts (xy 122.555 107.95) (xy 122.555 109.855))
    (stroke (width 0) (type default))
  )
  (wire (pts (xy 158.75 99.06) (xy 161.29 99.06))
    (stroke (width 0) (type default))
  )
  (wire (pts (xy 161.29 107.95) (xy 151.13 107.95))
    (stroke (width 0) (type default))
  )
  (wire (pts (xy 151.13 62.23) (xy 151.13 59.69))
    (stroke (width 0) (type default))
  )
  (wire (pts (xy 140.97 46.355) (xy 151.13 46.355))
    (stroke (width 0) (type default))
  )
  (wire (pts (xy 124.46 140.97) (xy 123.19 140.97))
    (stroke (width 0) (type default))
  )
  (wire (pts (xy 149.86 62.23) (xy 151.13 62.23))
    (stroke (width 0) (type default))
  )
  (wire (pts (xy 127 93.98) (xy 128.27 93.98))
    (stroke (width 0) (type default))
  )
  (wire (pts (xy 149.86 146.05) (xy 149.86 143.51))
    (stroke (width 0) (type default))
  )
  (wire (pts (xy 149.86 96.52) (xy 151.13 96.52))
    (stroke (width 0) (type default))
  )

  (text "DC JACK\nreverse polarity protection\n" (at 109.22 123.19 90)
    (effects (font (size 1.27 1.27)) (justify left bottom))
  )

  (hierarchical_label "DC_MAIN_BUS" (shape input) (at 179.07 59.69 0) (fields_autoplaced)
    (effects (font (size 1.27 1.27)) (justify left))
  )
  (hierarchical_label "POE_12V" (shape input) (at 123.19 140.97 180) (fields_autoplaced)
    (effects (font (size 1.27 1.27)) (justify right))
  )
  (hierarchical_label "DC_IN" (shape input) (at 118.745 93.98 180) (fields_autoplaced)
    (effects (font (size 1.27 1.27)) (justify right))
  )
  (hierarchical_label "PD_VBUS" (shape input) (at 121.92 57.15 180) (fields_autoplaced)
    (effects (font (size 1.27 1.27)) (justify right))
  )

  (symbol (lib_id "kria-k26-devboard:1N4148WS") (at 122.555 104.775 270) (mirror x) (unit 1)
    (in_bom yes) (on_board yes) (dnp no) (fields_autoplaced)
    (property "Reference" "D21" (at 120.015 99.695 90)
      (effects (font (size 1.524 1.524)) (justify right))
    )
    (property "Value" "1N4148WS" (at 120.5738 106.1212 0)
      (effects (font (size 1.27 1.27) (thickness 0.15)) (justify left bottom) hide)
    )
    (property "Footprint" "kria-k26-devboard-footprints:D_SOD-323F" (at 127.635 99.695 0)
      (effects (font (size 1.27 1.27) (thickness 0.15)) (justify left bottom) hide)
    )
    (property "Datasheet" "https://www.onsemi.com/pub/Collateral/1N914BWS-D.pdf" (at 130.175 99.695 0)
      (effects (font (size 1.27 1.27) (thickness 0.15)) (justify left bottom) hide)
    )
    (property "MPN" "1N4148WS" (at 120.015 102.8699 90)
      (effects (font (size 1.27 1.27) (thickness 0.15)) (justify right))
    )
    (property "Manufacturer" "ON Semiconductor" (at 150.495 99.695 0)
      (effects (font (size 1.27 1.27) (thickness 0.15)) (justify left bottom) hide)
    )
    (property "Author" "Antmicro" (at 102.235 83.185 0)
      (effects (font (size 1.27 1.27) (thickness 0.15)) (justify left bottom) hide)
    )
    (property "License" "Apache-2.0" (at 99.695 83.185 0)
      (effects (font (size 1.27 1.27) (thickness 0.15)) (justify left bottom) hide)
    )
    (pin "A")
    (pin "K")
    (instances
      (project "kria-k26-devboard"
        (path ""
          (reference "D21") (unit 1)
        )
      )
    )
  )

  (symbol (lib_id "kria-k26-devboard:1N4148WS") (at 122.555 109.855 270) (unit 1)
    (in_bom yes) (on_board yes) (dnp no) (fields_autoplaced)
    (property "Reference" "D22" (at 119.38 112.395 90)
      (effects (font (size 1.524 1.524)) (justify right))
    )
    (property "Value" "1N4148WS" (at 120.5738 111.2012 0)
      (effects (font (size 1.27 1.27) (thickness 0.15)) (justify left bottom) hide)
    )
    (property "Footprint" "kria-k26-devboard-footprints:D_SOD-323F" (at 127.635 114.935 0)
      (effects (font (size 1.27 1.27) (thickness 0.15)) (justify left bottom) hide)
    )
    (property "Datasheet" "https://www.onsemi.com/pub/Collateral/1N914BWS-D.pdf" (at 130.175 114.935 0)
      (effects (font (size 1.27 1.27) (thickness 0.15)) (justify left bottom) hide)
    )
    (property "MPN" "1N4148WS" (at 119.38 115.5699 90)
      (effects (font (size 1.27 1.27) (thickness 0.15)) (justify right))
    )
    (property "Manufacturer" "ON Semiconductor" (at 150.495 114.935 0)
      (effects (font (size 1.27 1.27) (thickness 0.15)) (justify left bottom) hide)
    )
    (property "Author" "Antmicro" (at 102.235 131.445 0)
      (effects (font (size 1.27 1.27) (thickness 0.15)) (justify left bottom) hide)
    )
    (property "License" "Apache-2.0" (at 99.695 131.445 0)
      (effects (font (size 1.27 1.27) (thickness 0.15)) (justify left bottom) hide)
    )
    (pin "A")
    (pin "K")
    (instances
      (project "kria-k26-devboard"
        (path ""
          (reference "D22") (unit 1)
        )
      )
    )
  )

  (symbol (lib_id "kria-k26-devboard:PMEG3050EP,115") (at 135.89 46.355 0) (unit 1)
    (in_bom no) (on_board yes) (dnp yes)
    (property "Reference" "D24" (at 138.1125 40.64 0)
      (effects (font (size 1.524 1.524)))
    )
    (property "Value" "PMEG3050EP,115" (at 135.89 42.3926 0)
      (effects (font (size 1.27 1.27) (thickness 0.15)) (justify left bottom) hide)
    )
    (property "Footprint" "kria-k26-devboard-footprints:Nexperia_SOD128" (at 140.97 41.275 0)
      (effects (font (size 1.27 1.27) (thickness 0.15)) (justify left bottom) hide)
    )
    (property "Datasheet" "https://www.mouser.pl/datasheet/2/916/PMEG3050EP-2938519.pdf" (at 140.97 38.735 0)
      (effects (font (size 1.27 1.27) (thickness 0.15)) (justify left bottom) hide)
    )
    (property "MPN" "PMEG3050EP,115" (at 138.43 43.18 0)
      (effects (font (size 1.27 1.27) (thickness 0.15)))
    )
    (property "Manufacturer" "Nexperia" (at 140.97 18.415 0)
      (effects (font (size 1.27 1.27) (thickness 0.15)) (justify left bottom) hide)
    )
    (property "Author" "Antmicro" (at 157.48 66.675 0)
      (effects (font (size 1.27 1.27) (thickness 0.15)) (justify left bottom) hide)
    )
    (property "License" "Apache-2.0" (at 157.48 69.215 0)
      (effects (font (size 1.27 1.27) (thickness 0.15)) (justify left bottom) hide)
    )
    (property "DNP" "DNP" (at 135.255 47.625 0)
      (effects (font (size 1.27 1.27)))
    )
    (pin "1")
    (pin "2")
    (instances
      (project "kria-k26-devboard"
        (path ""
          (reference "D24") (unit 1)
        )
      )
    )
  )

  (symbol (lib_id "kria-k26-devboard:PMEG3050EP,115") (at 136.525 83.185 0) (unit 1)
    (in_bom no) (on_board yes) (dnp yes)
    (property "Reference" "D25" (at 138.7475 77.47 0)
      (effects (font (size 1.524 1.524)))
    )
    (property "Value" "PMEG3050EP,115" (at 136.525 79.2226 0)
      (effects (font (size 1.27 1.27) (thickness 0.15)) (justify left bottom) hide)
    )
    (property "Footprint" "kria-k26-devboard-footprints:Nexperia_SOD128" (at 141.605 78.105 0)
      (effects (font (size 1.27 1.27) (thickness 0.15)) (justify left bottom) hide)
    )
    (property "Datasheet" "https://www.mouser.pl/datasheet/2/916/PMEG3050EP-2938519.pdf" (at 141.605 75.565 0)
      (effects (font (size 1.27 1.27) (thickness 0.15)) (justify left bottom) hide)
    )
    (property "MPN" "PMEG3050EP,115" (at 139.065 80.01 0)
      (effects (font (size 1.27 1.27) (thickness 0.15)))
    )
    (property "Manufacturer" "Nexperia" (at 141.605 55.245 0)
      (effects (font (size 1.27 1.27) (thickness 0.15)) (justify left bottom) hide)
    )
    (property "Author" "Antmicro" (at 158.115 103.505 0)
      (effects (font (size 1.27 1.27) (thickness 0.15)) (justify left bottom) hide)
    )
    (property "License" "Apache-2.0" (at 158.115 106.045 0)
      (effects (font (size 1.27 1.27) (thickness 0.15)) (justify left bottom) hide)
    )
    (property "DNP" "DNP" (at 135.89 84.455 0)
      (effects (font (size 1.27 1.27)))
    )
    (pin "1")
    (pin "2")
    (instances
      (project "kria-k26-devboard"
        (path ""
          (reference "D25") (unit 1)
        )
      )
    )
  )

  (symbol (lib_id "kria-k26-devboard:PMEG3050EP,115") (at 133.985 130.81 0) (unit 1)
    (in_bom no) (on_board yes) (dnp yes)
    (property "Reference" "D23" (at 136.525 125.095 0)
      (effects (font (size 1.524 1.524)))
    )
    (property "Value" "PMEG3050EP,115" (at 133.985 126.8476 0)
      (effects (font (size 1.27 1.27) (thickness 0.15)) (justify left bottom) hide)
    )
    (property "Footprint" "kria-k26-devboard-footprints:Nexperia_SOD128" (at 139.065 125.73 0)
      (effects (font (size 1.27 1.27) (thickness 0.15)) (justify left bottom) hide)
    )
    (property "Datasheet" "https://www.mouser.pl/datasheet/2/916/PMEG3050EP-2938519.pdf" (at 139.065 123.19 0)
      (effects (font (size 1.27 1.27) (thickness 0.15)) (justify left bottom) hide)
    )
    (property "MPN" "PMEG3050EP,115" (at 136.8425 127.635 0)
      (effects (font (size 1.27 1.27) (thickness 0.15)))
    )
    (property "Manufacturer" "Nexperia" (at 139.065 102.87 0)
      (effects (font (size 1.27 1.27) (thickness 0.15)) (justify left bottom) hide)
    )
    (property "Author" "Antmicro" (at 155.575 151.13 0)
      (effects (font (size 1.27 1.27) (thickness 0.15)) (justify left bottom) hide)
    )
    (property "License" "Apache-2.0" (at 155.575 153.67 0)
      (effects (font (size 1.27 1.27) (thickness 0.15)) (justify left bottom) hide)
    )
    (property "DNP" "DNP" (at 133.35 132.08 0)
      (effects (font (size 1.27 1.27)))
    )
    (pin "1")
    (pin "2")
    (instances
      (project "kria-k26-devboard"
        (path ""
          (reference "D23") (unit 1)
        )
      )
    )
  )

  (symbol (lib_id "kria-k26-devboard:LTC4358CDE") (at 128.27 57.15 0) (unit 1)
    (in_bom yes) (on_board yes) (dnp no) (fields_autoplaced)
    (property "Reference" "U57" (at 139.065 49.53 0)
      (effects (font (size 1.524 1.524)))
    )
    (property "Value" "LTC4358CDE" (at 139.065 52.07 0)
      (effects (font (size 1.27 1.27) (thickness 0.15)))
    )
    (property "Footprint" "kria-k26-devboard-footprints:DFN-14-1EP_4x3mm_P0.5mm" (at 137.16 37.084 0)
      (effects (font (size 1.27 1.27) (thickness 0.15)) (justify left bottom) hide)
    )
    (property "Datasheet" "https://www.mouser.com/datasheet/2/609/4358fa-1270155.pdf" (at 125.73 41.91 0)
      (effects (font (size 1.27 1.27) (thickness 0.15)) (justify left bottom) hide)
    )
    (property "Manufacturer" "Analog Devices" (at 137.16 36.83 0)
      (effects (font (size 1.27 1.27) (thickness 0.15)) (justify left bottom) hide)
    )
    (property "MPN" "LTC4358CDE#PBF" (at 139.065 52.705 0)
      (effects (font (size 1.27 1.27) (thickness 0.15)) hide)
    )
    (property "Author" "Antmicro" (at 163.83 74.93 0)
      (effects (font (size 1.27 1.27) (thickness 0.15)) (justify left bottom) hide)
    )
    (property "License" "Apache-2.0" (at 163.83 77.47 0)
      (effects (font (size 1.27 1.27) (thickness 0.15)) (justify left bottom) hide)
    )
    (pin "1")
    (pin "10")
    (pin "11")
    (pin "12")
    (pin "13")
    (pin "14")
    (pin "15")
    (pin "2")
    (pin "3")
    (pin "4")
    (pin "5")
    (pin "6")
    (pin "7")
    (pin "8")
    (pin "9")
    (instances
      (project "kria-k26-devboard"
        (path ""
          (reference "U57") (unit 1)
        )
      )
    )
  )

  (symbol (lib_id "kria-k26-devboard:GND") (at 126.365 66.675 0) (unit 1)
    (in_bom yes) (on_board yes) (dnp no)
    (property "Reference" "#PWR0390" (at 126.365 73.025 0)
      (effects (font (size 1.27 1.27)) hide)
    )
    (property "Value" "GND" (at 126.492 71.0692 0)
      (effects (font (size 1.27 1.27)))
    )
    (property "Footprint" "" (at 135.255 74.295 0)
      (effects (font (size 1.27 1.27) (thickness 0.15)) (justify left bottom) hide)
    )
    (property "Datasheet" "" (at 135.255 79.375 0)
      (effects (font (size 1.27 1.27) (thickness 0.15)) (justify left bottom) hide)
    )
    (property "Author" "Antmicro" (at 135.255 74.295 0)
      (effects (font (size 1.27 1.27) (thickness 0.15)) (justify left bottom) hide)
    )
    (property "License" "Apache-2.0" (at 135.255 76.835 0)
      (effects (font (size 1.27 1.27) (thickness 0.15)) (justify left bottom) hide)
    )
    (pin "1")
    (instances
      (project "kria-k26-devboard"
        (path ""
          (reference "#PWR0390") (unit 1)
        )
      )
    )
  )

  (symbol (lib_id "kria-k26-devboard:C_100n_0402") (at 156.21 63.5 270) (unit 1)
    (in_bom yes) (on_board yes) (dnp no) (fields_autoplaced)
    (property "Reference" "C229" (at 158.75 64.7763 90)
      (effects (font (size 1.524 1.524)) (justify left))
    )
    (property "Value" "C_100n_0402" (at 152.4 63.5 0)
      (effects (font (size 1.27 1.27) (thickness 0.15)) (justify left bottom) hide)
    )
    (property "Footprint" "kria-k26-devboard-footprints:C_0402_1005Metric" (at 161.29 68.58 0)
      (effects (font (size 1.27 1.27) (thickness 0.15)) (justify left bottom) hide)
    )
    (property "Datasheet" "https://search.murata.co.jp/Ceramy/image/img/A01X/G101/ENG/GRM155R61H104KE14-01.pdf" (at 156.21 63.5 0)
      (effects (font (size 1.27 1.27) (thickness 0.15)) (justify left bottom) hide)
    )
    (property "Manufacturer" "Murata" (at 166.37 68.58 0)
      (effects (font (size 1.27 1.27) (thickness 0.15)) (justify left bottom) hide)
    )
    (property "MPN" "GRM155R61H104KE14D" (at 163.83 68.58 0)
      (effects (font (size 1.27 1.27) (thickness 0.15)) (justify left bottom) hide)
    )
    (property "Val" "100n" (at 158.75 67.9512 90)
      (effects (font (size 1.27 1.27) (thickness 0.15)) (justify left))
    )
    (property "License" "Apache-2.0" (at 133.35 83.82 0)
      (effects (font (size 1.27 1.27) (thickness 0.15)) (justify left bottom) hide)
    )
    (property "Author" "Antmicro" (at 130.81 83.82 0)
      (effects (font (size 1.27 1.27) (thickness 0.15)) (justify left bottom) hide)
    )
    (property "Voltage" "50V" (at 128.27 83.82 0)
      (effects (font (size 1.27 1.27)) (justify left bottom) hide)
    )
    (property "Dielectric" "X5R" (at 125.73 83.82 0)
      (effects (font (size 1.27 1.27)) (justify left bottom) hide)
    )
    (pin "1")
    (pin "2")
    (instances
      (project "kria-k26-devboard"
        (path ""
          (reference "C229") (unit 1)
        )
      )
    )
  )

  (symbol (lib_id "kria-k26-devboard:LTC4358CDE") (at 128.27 93.98 0) (unit 1)
    (in_bom yes) (on_board yes) (dnp no) (fields_autoplaced)
    (property "Reference" "U58" (at 139.065 86.36 0)
      (effects (font (size 1.524 1.524)))
    )
    (property "Value" "LTC4358CDE" (at 139.065 88.9 0)
      (effects (font (size 1.27 1.27) (thickness 0.15)))
    )
    (property "Footprint" "kria-k26-devboard-footprints:DFN-14-1EP_4x3mm_P0.5mm" (at 137.16 73.914 0)
      (effects (font (size 1.27 1.27) (thickness 0.15)) (justify left bottom) hide)
    )
    (property "Datasheet" "https://www.mouser.com/datasheet/2/609/4358fa-1270155.pdf" (at 125.73 78.74 0)
      (effects (font (size 1.27 1.27) (thickness 0.15)) (justify left bottom) hide)
    )
    (property "Manufacturer" "Analog Devices" (at 137.16 73.66 0)
      (effects (font (size 1.27 1.27) (thickness 0.15)) (justify left bottom) hide)
    )
    (property "MPN" "LTC4358CDE#PBF" (at 139.065 89.535 0)
      (effects (font (size 1.27 1.27) (thickness 0.15)) hide)
    )
    (property "Author" "Antmicro" (at 163.83 111.76 0)
      (effects (font (size 1.27 1.27) (thickness 0.15)) (justify left bottom) hide)
    )
    (property "License" "Apache-2.0" (at 163.83 114.3 0)
      (effects (font (size 1.27 1.27) (thickness 0.15)) (justify left bottom) hide)
    )
    (pin "1")
    (pin "10")
    (pin "11")
    (pin "12")
    (pin "13")
    (pin "14")
    (pin "15")
    (pin "2")
    (pin "3")
    (pin "4")
    (pin "5")
    (pin "6")
    (pin "7")
    (pin "8")
    (pin "9")
    (instances
      (project "kria-k26-devboard"
        (path ""
          (reference "U58") (unit 1)
        )
      )
    )
  )

  (symbol (lib_id "kria-k26-devboard:GND") (at 122.555 117.475 0) (unit 1)
    (in_bom yes) (on_board yes) (dnp no)
    (property "Reference" "#PWR0388" (at 122.555 123.825 0)
      (effects (font (size 1.27 1.27)) hide)
    )
    (property "Value" "GND" (at 122.682 121.8692 0)
      (effects (font (size 1.27 1.27)))
    )
    (property "Footprint" "" (at 131.445 125.095 0)
      (effects (font (size 1.27 1.27) (thickness 0.15)) (justify left bottom) hide)
    )
    (property "Datasheet" "" (at 131.445 130.175 0)
      (effects (font (size 1.27 1.27) (thickness 0.15)) (justify left bottom) hide)
    )
    (property "Author" "Antmicro" (at 131.445 125.095 0)
      (effects (font (size 1.27 1.27) (thickness 0.15)) (justify left bottom) hide)
    )
    (property "License" "Apache-2.0" (at 131.445 127.635 0)
      (effects (font (size 1.27 1.27) (thickness 0.15)) (justify left bottom) hide)
    )
    (pin "1")
    (instances
      (project "kria-k26-devboard"
        (path ""
          (reference "#PWR0388") (unit 1)
        )
      )
    )
  )

  (symbol (lib_id "kria-k26-devboard:C_100n_0402") (at 161.29 101.6 270) (unit 1)
    (in_bom yes) (on_board yes) (dnp no)
    (property "Reference" "C230" (at 161.925 102.235 90)
      (effects (font (size 1.524 1.524)) (justify left))
    )
    (property "Value" "C_100n_0402" (at 157.48 101.6 0)
      (effects (font (size 1.27 1.27) (thickness 0.15)) (justify left bottom) hide)
    )
    (property "Footprint" "kria-k26-devboard-footprints:C_0402_1005Metric" (at 166.37 106.68 0)
      (effects (font (size 1.27 1.27) (thickness 0.15)) (justify left bottom) hide)
    )
    (property "Datasheet" "https://search.murata.co.jp/Ceramy/image/img/A01X/G101/ENG/GRM155R61H104KE14-01.pdf" (at 161.29 101.6 0)
      (effects (font (size 1.27 1.27) (thickness 0.15)) (justify left bottom) hide)
    )
    (property "Manufacturer" "Murata" (at 171.45 106.68 0)
      (effects (font (size 1.27 1.27) (thickness 0.15)) (justify left bottom) hide)
    )
    (property "MPN" "GRM155R61H104KE14D" (at 168.91 106.68 0)
      (effects (font (size 1.27 1.27) (thickness 0.15)) (justify left bottom) hide)
    )
    (property "Val" "100n" (at 161.925 106.045 90)
      (effects (font (size 1.27 1.27) (thickness 0.15)) (justify left))
    )
    (property "License" "Apache-2.0" (at 138.43 121.92 0)
      (effects (font (size 1.27 1.27) (thickness 0.15)) (justify left bottom) hide)
    )
    (property "Author" "Antmicro" (at 135.89 121.92 0)
      (effects (font (size 1.27 1.27) (thickness 0.15)) (justify left bottom) hide)
    )
    (property "Voltage" "50V" (at 133.35 121.92 0)
      (effects (font (size 1.27 1.27)) (justify left bottom) hide)
    )
    (property "Dielectric" "X5R" (at 130.81 121.92 0)
      (effects (font (size 1.27 1.27)) (justify left bottom) hide)
    )
    (pin "1")
    (pin "2")
    (instances
      (project "kria-k26-devboard"
        (path ""
          (reference "C230") (unit 1)
        )
      )
    )
  )

  (symbol (lib_id "kria-k26-devboard:R_100R_0402") (at 158.75 99.06 180) (unit 1)
    (in_bom yes) (on_board yes) (dnp no)
    (property "Reference" "R148" (at 156.21 95.25 0)
      (effects (font (size 1.524 1.524)))
    )
    (property "Value" "R_100R_0402" (at 158.75 95.25 0)
      (effects (font (size 1.27 1.27) (thickness 0.15)) (justify left bottom) hide)
    )
    (property "Footprint" "kria-k26-devboard-footprints:R_0402_1005Metric" (at 153.67 104.14 0)
      (effects (font (size 1.27 1.27) (thickness 0.15)) (justify left bottom) hide)
    )
    (property "Datasheet" "https://www.bourns.com/docs/product-datasheets/cr.pdf" (at 158.75 99.06 0)
      (effects (font (size 1.27 1.27) (thickness 0.15)) (justify left bottom) hide)
    )
    (property "Manufacturer" "Bourns" (at 153.67 109.22 0)
      (effects (font (size 1.27 1.27) (thickness 0.15)) (justify left bottom) hide)
    )
    (property "MPN" "CR0402-FX-1000GLF" (at 153.67 106.68 0)
      (effects (font (size 1.27 1.27) (thickness 0.15)) (justify left bottom) hide)
    )
    (property "Val" "100R" (at 156.21 97.155 0)
      (effects (font (size 1.27 1.27) (thickness 0.15)))
    )
    (property "License" "Apache-2.0" (at 138.43 73.66 0)
      (effects (font (size 1.27 1.27) (thickness 0.15)) (justify left bottom) hide)
    )
    (property "Author" "Antmicro" (at 138.43 71.12 0)
      (effects (font (size 1.27 1.27) (thickness 0.15)) (justify left bottom) hide)
    )
    (property "Tolerance" "1%" (at 138.43 88.9 0)
      (effects (font (size 1.27 1.27)) (justify left bottom) hide)
    )
    (pin "1")
    (pin "2")
    (instances
      (project "kria-k26-devboard"
        (path ""
          (reference "R148") (unit 1)
        )
      )
    )
  )

  (symbol (lib_id "kria-k26-devboard:C_100n_0402") (at 151.13 101.6 270) (unit 1)
    (in_bom yes) (on_board yes) (dnp no)
    (property "Reference" "C227" (at 151.765 102.235 90)
      (effects (font (size 1.524 1.524)) (justify left))
    )
    (property "Value" "C_100n_0402" (at 147.32 101.6 0)
      (effects (font (size 1.27 1.27) (thickness 0.15)) (justify left bottom) hide)
    )
    (property "Footprint" "kria-k26-devboard-footprints:C_0402_1005Metric" (at 156.21 106.68 0)
      (effects (font (size 1.27 1.27) (thickness 0.15)) (justify left bottom) hide)
    )
    (property "Datasheet" "https://search.murata.co.jp/Ceramy/image/img/A01X/G101/ENG/GRM155R61H104KE14-01.pdf" (at 151.13 101.6 0)
      (effects (font (size 1.27 1.27) (thickness 0.15)) (justify left bottom) hide)
    )
    (property "Manufacturer" "Murata" (at 161.29 106.68 0)
      (effects (font (size 1.27 1.27) (thickness 0.15)) (justify left bottom) hide)
    )
    (property "MPN" "GRM155R61H104KE14D" (at 158.75 106.68 0)
      (effects (font (size 1.27 1.27) (thickness 0.15)) (justify left bottom) hide)
    )
    (property "Val" "100n" (at 151.765 106.045 90)
      (effects (font (size 1.27 1.27) (thickness 0.15)) (justify left))
    )
    (property "License" "Apache-2.0" (at 128.27 121.92 0)
      (effects (font (size 1.27 1.27) (thickness 0.15)) (justify left bottom) hide)
    )
    (property "Author" "Antmicro" (at 125.73 121.92 0)
      (effects (font (size 1.27 1.27) (thickness 0.15)) (justify left bottom) hide)
    )
    (property "Voltage" "50V" (at 123.19 121.92 0)
      (effects (font (size 1.27 1.27)) (justify left bottom) hide)
    )
    (property "Dielectric" "X5R" (at 120.65 121.92 0)
      (effects (font (size 1.27 1.27)) (justify left bottom) hide)
    )
    (pin "1")
    (pin "2")
    (instances
      (project "kria-k26-devboard"
        (path ""
          (reference "C227") (unit 1)
        )
      )
    )
  )

  (symbol (lib_id "kria-k26-devboard:LTC4358CDE") (at 125.73 140.97 0) (unit 1)
    (in_bom yes) (on_board yes) (dnp no) (fields_autoplaced)
    (property "Reference" "U56" (at 136.525 153.67 0)
      (effects (font (size 1.524 1.524)))
    )
    (property "Value" "LTC4358CDE" (at 136.525 156.21 0)
      (effects (font (size 1.27 1.27) (thickness 0.15)))
    )
    (property "Footprint" "kria-k26-devboard-footprints:DFN-14-1EP_4x3mm_P0.5mm" (at 134.62 120.904 0)
      (effects (font (size 1.27 1.27) (thickness 0.15)) (justify left bottom) hide)
    )
    (property "Datasheet" "https://www.mouser.com/datasheet/2/609/4358fa-1270155.pdf" (at 123.19 125.73 0)
      (effects (font (size 1.27 1.27) (thickness 0.15)) (justify left bottom) hide)
    )
    (property "Manufacturer" "Analog Devices" (at 134.62 120.65 0)
      (effects (font (size 1.27 1.27) (thickness 0.15)) (justify left bottom) hide)
    )
    (property "MPN" "LTC4358CDE#PBF" (at 136.525 136.525 0)
      (effects (font (size 1.27 1.27) (thickness 0.15)) hide)
    )
    (property "Author" "Antmicro" (at 161.29 158.75 0)
      (effects (font (size 1.27 1.27) (thickness 0.15)) (justify left bottom) hide)
    )
    (property "License" "Apache-2.0" (at 161.29 161.29 0)
      (effects (font (size 1.27 1.27) (thickness 0.15)) (justify left bottom) hide)
    )
    (pin "1")
    (pin "10")
    (pin "11")
    (pin "12")
    (pin "13")
    (pin "14")
    (pin "15")
    (pin "2")
    (pin "3")
    (pin "4")
    (pin "5")
    (pin "6")
    (pin "7")
    (pin "8")
    (pin "9")
    (instances
      (project "kria-k26-devboard"
        (path ""
          (reference "U56") (unit 1)
        )
      )
    )
  )

  (symbol (lib_id "kria-k26-devboard:GND") (at 123.825 149.86 0) (unit 1)
    (in_bom yes) (on_board yes) (dnp no)
    (property "Reference" "#PWR0389" (at 123.825 156.21 0)
      (effects (font (size 1.27 1.27)) hide)
    )
    (property "Value" "GND" (at 123.952 154.2542 0)
      (effects (font (size 1.27 1.27)))
    )
    (property "Footprint" "" (at 132.715 157.48 0)
      (effects (font (size 1.27 1.27) (thickness 0.15)) (justify left bottom) hide)
    )
    (property "Datasheet" "" (at 132.715 162.56 0)
      (effects (font (size 1.27 1.27) (thickness 0.15)) (justify left bottom) hide)
    )
    (property "Author" "Antmicro" (at 132.715 157.48 0)
      (effects (font (size 1.27 1.27) (thickness 0.15)) (justify left bottom) hide)
    )
    (property "License" "Apache-2.0" (at 132.715 160.02 0)
      (effects (font (size 1.27 1.27) (thickness 0.15)) (justify left bottom) hide)
    )
    (pin "1")
    (instances
      (project "kria-k26-devboard"
        (path ""
          (reference "#PWR0389") (unit 1)
        )
      )
    )
  )

  (symbol (lib_id "kria-k26-devboard:C_100n_0402") (at 153.67 145.415 270) (unit 1)
    (in_bom yes) (on_board yes) (dnp no) (fields_autoplaced)
    (property "Reference" "C228" (at 156.21 146.6913 90)
      (effects (font (size 1.524 1.524)) (justify left))
    )
    (property "Value" "C_100n_0402" (at 149.86 145.415 0)
      (effects (font (size 1.27 1.27) (thickness 0.15)) (justify left bottom) hide)
    )
    (property "Footprint" "kria-k26-devboard-footprints:C_0402_1005Metric" (at 158.75 150.495 0)
      (effects (font (size 1.27 1.27) (thickness 0.15)) (justify left bottom) hide)
    )
    (property "Datasheet" "https://search.murata.co.jp/Ceramy/image/img/A01X/G101/ENG/GRM155R61H104KE14-01.pdf" (at 153.67 145.415 0)
      (effects (font (size 1.27 1.27) (thickness 0.15)) (justify left bottom) hide)
    )
    (property "Manufacturer" "Murata" (at 163.83 150.495 0)
      (effects (font (size 1.27 1.27) (thickness 0.15)) (justify left bottom) hide)
    )
    (property "MPN" "GRM155R61H104KE14D" (at 161.29 150.495 0)
      (effects (font (size 1.27 1.27) (thickness 0.15)) (justify left bottom) hide)
    )
    (property "Val" "100n" (at 156.21 149.8662 90)
      (effects (font (size 1.27 1.27) (thickness 0.15)) (justify left))
    )
    (property "License" "Apache-2.0" (at 130.81 165.735 0)
      (effects (font (size 1.27 1.27) (thickness 0.15)) (justify left bottom) hide)
    )
    (property "Author" "Antmicro" (at 128.27 165.735 0)
      (effects (font (size 1.27 1.27) (thickness 0.15)) (justify left bottom) hide)
    )
    (property "Voltage" "50V" (at 125.73 165.735 0)
      (effects (font (size 1.27 1.27)) (justify left bottom) hide)
    )
    (property "Dielectric" "X5R" (at 123.19 165.735 0)
      (effects (font (size 1.27 1.27)) (justify left bottom) hide)
    )
    (pin "1")
    (pin "2")
    (instances
      (project "kria-k26-devboard"
        (path ""
          (reference "C228") (unit 1)
        )
      )
    )
  )

  (symbol (lib_id "kria-k26-devboard:TP_0.75mm_SMD") (at 166.37 58.42 90) (unit 1)
    (in_bom yes) (on_board yes) (dnp no) (fields_autoplaced)
    (property "Reference" "TP43" (at 168.91 55.2449 90)
      (effects (font (size 1.27 1.27)) (justify right))
    )
    (property "Value" "TP_0.75mm_SMD" (at 168.91 58.42 0)
      (effects (font (size 1.27 1.27) (thickness 0.15)) (justify left bottom) hide)
    )
    (property "Footprint" "kria-k26-devboard-footprints:TP_SMD_0.75mm" (at 161.29 53.34 0)
      (effects (font (size 1.27 1.27) (thickness 0.15)) (justify left bottom) hide)
    )
    (property "Datasheet" "" (at 158.75 53.34 0)
      (effects (font (size 1.27 1.27) (thickness 0.15)) (justify left bottom) hide)
    )
    (property "MPN" "" (at 166.37 58.42 0)
      (effects (font (size 1.27 1.27) (thickness 0.15)) (justify left bottom) hide)
    )
    (property "Manufacturer" "" (at 166.37 58.42 0)
      (effects (font (size 1.27 1.27) (thickness 0.15)) (justify left bottom) hide)
    )
    (property "Author" "Antmicro" (at 181.61 43.18 0)
      (effects (font (size 1.27 1.27) (thickness 0.15)) (justify left bottom) hide)
    )
    (property "License" "Apache-2.0" (at 184.15 43.18 0)
      (effects (font (size 1.27 1.27) (thickness 0.15)) (justify left bottom) hide)
    )
    (pin "1")
    (instances
      (project "kria-k26-devboard"
        (path ""
          (reference "TP43") (unit 1)
        )
      )
    )
  )

  (symbol (lib_id "kria-k26-devboard:GND") (at 156.21 68.58 0) (unit 1)
    (in_bom yes) (on_board yes) (dnp no)
    (property "Reference" "#PWR0130" (at 156.21 74.93 0)
      (effects (font (size 1.27 1.27)) hide)
    )
    (property "Value" "GND" (at 156.337 72.9742 0)
      (effects (font (size 1.27 1.27)))
    )
    (property "Footprint" "" (at 165.1 76.2 0)
      (effects (font (size 1.27 1.27) (thickness 0.15)) (justify left bottom) hide)
    )
    (property "Datasheet" "" (at 165.1 81.28 0)
      (effects (font (size 1.27 1.27) (thickness 0.15)) (justify left bottom) hide)
    )
    (property "Author" "Antmicro" (at 165.1 76.2 0)
      (effects (font (size 1.27 1.27) (thickness 0.15)) (justify left bottom) hide)
    )
    (property "License" "Apache-2.0" (at 165.1 78.74 0)
      (effects (font (size 1.27 1.27) (thickness 0.15)) (justify left bottom) hide)
    )
    (pin "1")
    (instances
      (project "kria-k26-devboard"
        (path ""
          (reference "#PWR0130") (unit 1)
        )
      )
    )
  )

  (symbol (lib_id "kria-k26-devboard:GND") (at 153.67 150.495 0) (unit 1)
    (in_bom yes) (on_board yes) (dnp no)
    (property "Reference" "#PWR0129" (at 153.67 156.845 0)
      (effects (font (size 1.27 1.27)) hide)
    )
    (property "Value" "GND" (at 153.797 154.8892 0)
      (effects (font (size 1.27 1.27)))
    )
    (property "Footprint" "" (at 162.56 158.115 0)
      (effects (font (size 1.27 1.27) (thickness 0.15)) (justify left bottom) hide)
    )
    (property "Datasheet" "" (at 162.56 163.195 0)
      (effects (font (size 1.27 1.27) (thickness 0.15)) (justify left bottom) hide)
    )
    (property "Author" "Antmicro" (at 162.56 158.115 0)
      (effects (font (size 1.27 1.27) (thickness 0.15)) (justify left bottom) hide)
    )
    (property "License" "Apache-2.0" (at 162.56 160.655 0)
      (effects (font (size 1.27 1.27) (thickness 0.15)) (justify left bottom) hide)
    )
    (pin "1")
    (instances
      (project "kria-k26-devboard"
        (path ""
          (reference "#PWR0129") (unit 1)
        )
      )
    )
  )
)
